(kicad_pcb
	(version 20221018)
	(generator pcbnew)
	(general
    (thickness 1.62)
  )
	(paper "A4")
	(title_block
    (title "ECP5 - Datacenter Secure Control Module (DC-SCM)")
    (date "2024-07-01")
    (rev "1.2.1")
		(comment 9 "footprints 212-216 of 506")
	)
	(layers
    (0 "F.Cu" signal)
    (1 "In1.Cu" power)
    (2 "In2.Cu" signal)
    (3 "In3.Cu" power)
    (4 "In4.Cu" power)
    (5 "In5.Cu" signal)
    (6 "In6.Cu" power)
    (31 "B.Cu" signal)
    (32 "B.Adhes" user "B.Adhesive")
    (33 "F.Adhes" user "F.Adhesive")
    (34 "B.Paste" user)
    (35 "F.Paste" user)
    (36 "B.SilkS" user "B.Silkscreen")
    (37 "F.SilkS" user "F.Silkscreen")
    (38 "B.Mask" user)
    (39 "F.Mask" user)
    (40 "Dwgs.User" user "User.Drawings")
    (41 "Cmts.User" user "User.Comments")
    (42 "Eco1.User" user "User.Eco1")
    (43 "Eco2.User" user "User.Eco2")
    (44 "Edge.Cuts" user)
    (45 "Margin" user)
    (46 "B.CrtYd" user "B.Courtyard")
    (47 "F.CrtYd" user "F.Courtyard")
    (48 "B.Fab" user)
    (49 "F.Fab" user)
  )
	(footprint "antmicro-footprints:Spacer_Drill3.7mm_H2.5mm_9774025151R" (layer "F.Cu")
    (at 129.511 81.495)
    (property "Author" "Antmicro")
    (property "License" "Apache-2.0")
    (property "MPN" "9774025151R")
    (property "Manufacturer" "Würth Elektronik")
    (property "Public" "False")
    (property "Sheetfile" "pcie-conn.kicad_sch")
    (property "Sheetname" "PCIe-connector")
    (property "ki_description" "Spacer, SMT, Non Stop, Steel, Swage Round, 5.1 mm x 2.5 mm, M2.5 Thread, WA-SMSI Series")
    (property "ki_keywords" "MECHANICAL, SPACER")
    (solder_paste_ratio -0.1)
    (attr smd)
    (fp_text reference "H1" (at 0 -3.2) (layer "F.SilkS")
        (effects (font (size 0.7 0.7) (thickness 0.15)) (justify left bottom))
    )
    (fp_text value "Spacer_Drill3.7mm_H2.5mm_9774025151R" (at 0 4) (layer "F.Fab")
        (effects (font (size 0.7 0.7) (thickness 0.15)) (justify left bottom))
    )
    (fp_text user "License: Apache-2.0" (at -2.75 8.25) (layer "F.Fab") hide
        (effects (font (size 0.7 0.7) (thickness 0.15)) (justify left bottom))
    )
    (fp_text user "${REFERENCE}" (at -2.75 5.5) (layer "F.Fab") hide
        (effects (font (size 0.7 0.7) (thickness 0.15)) (justify left bottom))
    )
    (fp_text user "Author: Antmicro" (at -2.75 6.75) (layer "F.Fab") hide
        (effects (font (size 0.7 0.7) (thickness 0.15)) (justify left bottom))
    )
    (fp_circle (center 0 0) (end 0 -3.05)
      (stroke (width 0.05) (type solid)) (fill none) (layer "F.CrtYd"))
    (pad "" smd custom (at -1.71 -1.71) (size 0.62 0.62) (layers "F.Paste")
      (thermal_bridge_angle 90)
      (options (clearance outline) (anchor circle))
      (primitives
        (gr_arc (start -0.250195 1.279127) (mid 0.285453 0.294389) (end 1.266786 -0.24747) (width 0.2))
        (gr_arc (start -0.34334 1.279127) (mid 0.218448 0.232561) (end 1.259603 -0.339191) (width 0.2))
        (gr_arc (start -0.436309 1.279127) (mid 0.152481 0.169693) (end 1.255279 -0.431435) (width 0.2))
        (gr_arc (start -0.529126 1.279127) (mid 0.087542 0.105784) (end 1.253811 -0.524161) (width 0.2))
        (gr_arc (start -0.621807 1.279127) (mid 0.0309 0.033527) (end 1.275473 -0.621136) (width 0.2))
        (gr_arc (start -0.71437 1.279127) (mid -0.037758 -0.026651) (end 1.263664 -0.711602) (width 0.2))
        (gr_arc (start -0.806826 1.279127) (mid -0.105837 -0.087395) (end 1.253435 -0.802342) (width 0.2))
        (gr_arc (start -0.899187 1.279127) (mid -0.165236 -0.156885) (end 1.267475 -0.897258) (width 0.2))
        (gr_arc (start -0.991463 1.279127) (mid -0.228522 -0.222449) (end 1.270645 -0.990112) (width 0.2))
        (gr_arc (start -1.083663 1.279127) (mid -0.294507 -0.285313) (end 1.266278 -1.081674) (width 0.2))
        (gr_line (start 1.279127 -0.250195) (end 1.279127 -1.083663) (width 0.2))
        (gr_line (start -0.250195 1.279127) (end -1.083663 1.279127) (width 0.2))
      ))
    (pad "" smd custom (at -1.71 1.699 90) (size 0.62 0.62) (layers "F.Paste")
      (thermal_bridge_angle 90)
      (options (clearance outline) (anchor circle))
      (primitives
        (gr_arc (start -0.250195 1.279127) (mid 0.285453 0.294389) (end 1.266786 -0.24747) (width 0.2))
        (gr_arc (start -0.34334 1.279127) (mid 0.218448 0.232561) (end 1.259603 -0.339191) (width 0.2))
        (gr_arc (start -0.436309 1.279127) (mid 0.152481 0.169693) (end 1.255279 -0.431435) (width 0.2))
        (gr_arc (start -0.529126 1.279127) (mid 0.087542 0.105784) (end 1.253811 -0.524161) (width 0.2))
        (gr_arc (start -0.621807 1.279127) (mid 0.0309 0.033527) (end 1.275473 -0.621136) (width 0.2))
        (gr_arc (start -0.71437 1.279127) (mid -0.037758 -0.026651) (end 1.263664 -0.711602) (width 0.2))
        (gr_arc (start -0.806826 1.279127) (mid -0.105837 -0.087395) (end 1.253435 -0.802342) (width 0.2))
        (gr_arc (start -0.899187 1.279127) (mid -0.165236 -0.156885) (end 1.267475 -0.897258) (width 0.2))
        (gr_arc (start -0.991463 1.279127) (mid -0.228522 -0.222449) (end 1.270645 -0.990112) (width 0.2))
        (gr_arc (start -1.083663 1.279127) (mid -0.294507 -0.285313) (end 1.266278 -1.081674) (width 0.2))
        (gr_line (start 1.279127 -0.250195) (end 1.279127 -1.083663) (width 0.2))
        (gr_line (start -0.250195 1.279127) (end -1.083663 1.279127) (width 0.2))
      ))
    (pad "" smd custom (at 1.699 -1.71 270) (size 0.62 0.62) (layers "F.Paste")
      (thermal_bridge_angle 90)
      (options (clearance outline) (anchor circle))
      (primitives
        (gr_arc (start -0.250195 1.279127) (mid 0.285453 0.294389) (end 1.266786 -0.24747) (width 0.2))
        (gr_arc (start -0.34334 1.279127) (mid 0.218448 0.232561) (end 1.259603 -0.339191) (width 0.2))
        (gr_arc (start -0.436309 1.279127) (mid 0.152481 0.169693) (end 1.255279 -0.431435) (width 0.2))
        (gr_arc (start -0.529126 1.279127) (mid 0.087542 0.105784) (end 1.253811 -0.524161) (width 0.2))
        (gr_arc (start -0.621807 1.279127) (mid 0.0309 0.033527) (end 1.275473 -0.621136) (width 0.2))
        (gr_arc (start -0.71437 1.279127) (mid -0.037758 -0.026651) (end 1.263664 -0.711602) (width 0.2))
        (gr_arc (start -0.806826 1.279127) (mid -0.105837 -0.087395) (end 1.253435 -0.802342) (width 0.2))
        (gr_arc (start -0.899187 1.279127) (mid -0.165236 -0.156885) (end 1.267475 -0.897258) (width 0.2))
        (gr_arc (start -0.991463 1.279127) (mid -0.228522 -0.222449) (end 1.270645 -0.990112) (width 0.2))
        (gr_arc (start -1.083663 1.279127) (mid -0.294507 -0.285313) (end 1.266278 -1.081674) (width 0.2))
        (gr_line (start 1.279127 -0.250195) (end 1.279127 -1.083663) (width 0.2))
        (gr_line (start -0.250195 1.279127) (end -1.083663 1.279127) (width 0.2))
      ))
    (pad "" smd custom (at 1.699 1.699 180) (size 0.62 0.62) (layers "F.Paste")
      (thermal_bridge_angle 90)
      (options (clearance outline) (anchor circle))
      (primitives
        (gr_arc (start -0.250195 1.279127) (mid 0.285453 0.294389) (end 1.266786 -0.24747) (width 0.2))
        (gr_arc (start -0.34334 1.279127) (mid 0.218448 0.232561) (end 1.259603 -0.339191) (width 0.2))
        (gr_arc (start -0.436309 1.279127) (mid 0.152481 0.169693) (end 1.255279 -0.431435) (width 0.2))
        (gr_arc (start -0.529126 1.279127) (mid 0.087542 0.105784) (end 1.253811 -0.524161) (width 0.2))
        (gr_arc (start -0.621807 1.279127) (mid 0.0309 0.033527) (end 1.275473 -0.621136) (width 0.2))
        (gr_arc (start -0.71437 1.279127) (mid -0.037758 -0.026651) (end 1.263664 -0.711602) (width 0.2))
        (gr_arc (start -0.806826 1.279127) (mid -0.105837 -0.087395) (end 1.253435 -0.802342) (width 0.2))
        (gr_arc (start -0.899187 1.279127) (mid -0.165236 -0.156885) (end 1.267475 -0.897258) (width 0.2))
        (gr_arc (start -0.991463 1.279127) (mid -0.228522 -0.222449) (end 1.270645 -0.990112) (width 0.2))
        (gr_arc (start -1.083663 1.279127) (mid -0.294507 -0.285313) (end 1.266278 -1.081674) (width 0.2))
        (gr_line (start 1.279127 -0.250195) (end 1.279127 -1.083663) (width 0.2))
        (gr_line (start -0.250195 1.279127) (end -1.083663 1.279127) (width 0.2))
      ))
    (pad "1" thru_hole circle (at 0 0) (size 6 6) (drill 3.7) (layers "*.Cu" "*.Mask")
      (net 778 "unconnected-(H1-Pad1)") (pintype "passive+no_connect") (solder_paste_margin_ratio -0.05))
  )
	(footprint "antmicro-footprints:R_0402_1005Metric" (layer "F.Cu")
    (at 90.7 88.7)
    (descr "Resistor SMD 0402")
    (tags "resistor SMD 0402")
    (property "Author" "Antmicro")
    (property "License" "Apache-2.0")
    (property "MPN" "CR0402-FX-3163GLF")
    (property "Manufacturer" "Bourns")
    (property "Public" "False")
    (property "Sheetfile" "power-supply.kicad_sch")
    (property "Sheetname" "Power supply")
    (property "Tolerance" "1%")
    (property "Val" "316k")
    (property "ki_description" "SMD Chip Resistor")
    (property "ki_keywords" "0402, SMT, RESISTOR, PASSIVE")
    (attr smd)
    (fp_text reference "R45" (at 2.1 0.5) (layer "F.SilkS")
        (effects (font (size 0.7 0.7) (thickness 0.15)))
    )
    (fp_text value "R_316k_0402" (at 0 1.17) (layer "F.Fab")
        (effects (font (size 1 1) (thickness 0.15)))
    )
    (fp_text user "Author: Antmicro" (at -0.95 4.169) (layer "F.Fab") hide
        (effects (font (size 0.7 0.7) (thickness 0.15)) (justify left bottom))
    )
    (fp_text user "${REFERENCE}" (at 0 0) (layer "F.Fab")
        (effects (font (size 0.25 0.25) (thickness 0.04)))
    )
    (fp_text user "License: Apache-2.0" (at -0.95 5.169) (layer "F.Fab") hide
        (effects (font (size 0.7 0.7) (thickness 0.15)) (justify left bottom))
    )
    (fp_rect (start -0.925 -0.47) (end 0.925 0.47)
      (stroke (width 0.05) (type default)) (fill none) (layer "F.CrtYd"))
    (fp_rect (start -0.5 -0.25) (end 0.5 0.25)
      (stroke (width 0.15) (type solid)) (fill none) (layer "F.Fab"))
    (pad "1" smd roundrect (at -0.48 0) (size 0.59 0.64) (layers "F.Cu" "F.Paste" "F.Mask") (roundrect_rratio 0.25)
      (net 301 "Net-(U16-FB)") (pintype "passive"))
    (pad "2" smd roundrect (at 0.48 0) (size 0.59 0.64) (layers "F.Cu" "F.Paste" "F.Mask") (roundrect_rratio 0.25)
      (net 359 "Net-(C122-Pad2)") (pintype "passive"))
  )
	(footprint "antmicro-footprints:USON-14_3.5x1.35_P0.5mm" (layer "F.Cu")
    (at 137.53 75.23 90)
    (descr "JEDEC MO-229")
    (property "Author" "Antmicro")
    (property "License" "Apache-2.0")
    (property "MPN" "SP3011-06UTG")
    (property "Manufacturer" "Littelfuse")
    (property "Sheetfile" "interfaces.kicad_sch")
    (property "Sheetname" "Interfaces")
    (property "ki_description" "TVS diode array, 8 kV, USON-14, 6 V, 0.4 pF")
    (property "ki_keywords" "SMT, DIODE, SEMICONDUCTOR, TVS, ESD")
    (attr smd)
    (fp_text reference "D2" (at -0.645 -2.05 90) (layer "F.SilkS")
        (effects (font (size 0.7 0.7) (thickness 0.15)) (justify left bottom))
    )
    (fp_text value "SP3011-06UTG" (at -1.3 3 90) (layer "F.Fab")
        (effects (font (size 0.7 0.7) (thickness 0.15)) (justify left bottom))
    )
    (fp_text user "." (at -0.9 -2.25 90) (layer "F.SilkS")
        (effects (font (size 1 1) (thickness 0.15)))
    )
    (fp_text user "Author: Antmicro" (at -1.3 5.4 90) (layer "F.Fab") hide
        (effects (font (size 0.7 0.7) (thickness 0.15)) (justify left bottom))
    )
    (fp_text user "${REFERENCE}" (at -1.3 4.2 90) (layer "F.Fab") hide
        (effects (font (size 0.7 0.7) (thickness 0.15)) (justify left bottom))
    )
    (fp_text user "License: Apache-2.0" (at -1.3 6.6 90) (layer "F.Fab") hide
        (effects (font (size 0.7 0.7) (thickness 0.15)) (justify left bottom))
    )
    (fp_line (start -0.8 1.75) (end 0.8 1.75)
      (stroke (width 0.12) (type solid)) (layer "F.SilkS"))
    (fp_line (start -0.4 -1.75) (end 0.8 -1.75)
      (stroke (width 0.12) (type solid)) (layer "F.SilkS"))
    (fp_rect (start 1 -1.9) (end -0.95 1.9)
      (stroke (width 0.05) (type solid)) (fill none) (layer "F.CrtYd"))
    (fp_line (start -0.7 -1.55) (end -0.5 -1.75)
      (stroke (width 0.1) (type solid)) (layer "F.Fab"))
    (fp_line (start -0.7 1.75) (end -0.7 -1.55)
      (stroke (width 0.1) (type solid)) (layer "F.Fab"))
    (fp_line (start -0.5 -1.75) (end 0.65 -1.75)
      (stroke (width 0.1) (type solid)) (layer "F.Fab"))
    (fp_line (start 0.65 -1.75) (end 0.65 1.75)
      (stroke (width 0.1) (type solid)) (layer "F.Fab"))
    (fp_line (start 0.65 1.75) (end -0.7 1.75)
      (stroke (width 0.1) (type solid)) (layer "F.Fab"))
    (pad "1" smd roundrect (at -0.623 -1.5) (size 0.2 0.5) (layers "F.Cu" "F.Paste" "F.Mask") (roundrect_rratio 0.25)
      (chamfer_ratio 0.2) (chamfer bottom_left)
      (net 19 "JTAG_TDI") (pintype "passive"))
    (pad "2" smd roundrect (at -0.623 -1) (size 0.2 0.5) (layers "F.Cu" "F.Paste" "F.Mask") (roundrect_rratio 0.25)
      (net 20 "JTAG_TDO") (pintype "passive"))
    (pad "3" smd roundrect (at -0.623 -0.5) (size 0.2 0.5) (layers "F.Cu" "F.Paste" "F.Mask") (roundrect_rratio 0.25)
      (net 298 "unconnected-(D2-Pad12)") (pintype "passive+no_connect"))
    (pad "4" smd roundrect (at -0.623 0) (size 0.2 0.5) (layers "F.Cu" "F.Paste" "F.Mask") (roundrect_rratio 0.25)
      (net 297 "unconnected-(D2-Pad11)") (pintype "passive+no_connect"))
    (pad "5" smd roundrect (at -0.623 0.498) (size 0.2 0.5) (layers "F.Cu" "F.Paste" "F.Mask") (roundrect_rratio 0.25)
      (net 1 "GND") (pintype "passive"))
    (pad "6" smd roundrect (at -0.623 0.998) (size 0.2 0.5) (layers "F.Cu" "F.Paste" "F.Mask") (roundrect_rratio 0.25)
      (net 21 "JTAG_TCK") (pintype "passive"))
    (pad "7" smd roundrect (at -0.623 1.499) (size 0.2 0.5) (layers "F.Cu" "F.Paste" "F.Mask") (roundrect_rratio 0.25)
      (net 22 "JTAG_TMS") (pintype "passive"))
    (pad "8" smd roundrect (at 0.625 1.499) (size 0.2 0.5) (layers "F.Cu" "F.Paste" "F.Mask") (roundrect_rratio 0.25)
      (net 22 "JTAG_TMS") (pintype "passive"))
    (pad "9" smd roundrect (at 0.625 0.998) (size 0.2 0.5) (layers "F.Cu" "F.Paste" "F.Mask") (roundrect_rratio 0.25)
      (net 21 "JTAG_TCK") (pintype "passive"))
    (pad "10" smd roundrect (at 0.625 0.498) (size 0.2 0.5) (layers "F.Cu" "F.Paste" "F.Mask") (roundrect_rratio 0.25)
      (net 1 "GND") (pintype "passive"))
    (pad "11" smd roundrect (at 0.625 0) (size 0.2 0.5) (layers "F.Cu" "F.Paste" "F.Mask") (roundrect_rratio 0.25)
      (net 297 "unconnected-(D2-Pad11)") (pintype "passive+no_connect"))
    (pad "12" smd roundrect (at 0.625 -0.5) (size 0.2 0.5) (layers "F.Cu" "F.Paste" "F.Mask") (roundrect_rratio 0.25)
      (net 298 "unconnected-(D2-Pad12)") (pintype "passive+no_connect"))
    (pad "13" smd roundrect (at 0.625 -1) (size 0.2 0.5) (layers "F.Cu" "F.Paste" "F.Mask") (roundrect_rratio 0.25)
      (net 20 "JTAG_TDO") (pintype "passive"))
    (pad "14" smd roundrect (at 0.625 -1.5) (size 0.2 0.5) (layers "F.Cu" "F.Paste" "F.Mask") (roundrect_rratio 0.25)
      (net 19 "JTAG_TDI") (pintype "passive"))
  )
	(footprint "antmicro-footprints:Oscillator_SMD_ECS_3225MV_3.2x2.5x1.2mm" (layer "F.Cu")
    (at 88.4 113.5)
    (property "Author" "Antmicro")
    (property "License" "Apache-2.0")
    (property "MPN" "ECS-3225MVQ-1000CN-TR")
    (property "Manufacturer" "ECS Inc. International")
    (property "Public" "False")
    (property "Sheetfile" "fpga-banks.kicad_sch")
    (property "Sheetname" "FPGA banks")
    (property "Val" "100 MHz")
    (property "ki_description" "Oscillator, 100 MHz, CMOS, SMD, 3.2mm x 2.5mm, MultiVolt ECS-3225MVQ Series")
    (property "ki_keywords" "OSCILLATOR")
    (attr smd)
    (fp_text reference "Y1" (at -0.77 -2.255 unlocked) (layer "F.SilkS")
        (effects (font (size 0.7 0.7) (thickness 0.15)) (justify left bottom))
    )
    (fp_text value "Oscillator_100MHz_ECS_3225MV" (at 0 3.302 unlocked) (layer "F.Fab")
        (effects (font (size 0.7 0.7) (thickness 0.15)) (justify left bottom))
    )
    (fp_text user "${REFERENCE}" (at -2.2 6.502) (layer "F.Fab") hide
        (effects (font (size 0.7 0.7) (thickness 0.15)) (justify left bottom))
    )
    (fp_text user "License: Apache-2.0" (at -2.2 7.702) (layer "F.Fab") hide
        (effects (font (size 0.7 0.7) (thickness 0.15)) (justify left bottom))
    )
    (fp_text user "Author: Antmicro" (at -2.2 5.302) (layer "F.Fab") hide
        (effects (font (size 0.7 0.7) (thickness 0.15)) (justify left bottom))
    )
    (fp_line (start -1.25 -0.102) (end -1.25 0.102)
      (stroke (width 0.15) (type solid)) (layer "F.SilkS"))
    (fp_line (start 1.25 -0.102) (end 1.25 0.102)
      (stroke (width 0.15) (type solid)) (layer "F.SilkS"))
    (fp_circle (center -1.55 -1.6) (end -1.5 -1.6)
      (stroke (width 0.15) (type solid)) (fill solid) (layer "F.SilkS"))
    (fp_rect (start 1.5 -1.85) (end -1.5 1.85)
      (stroke (width 0.05) (type solid)) (fill none) (layer "F.CrtYd"))
    (fp_line (start -1.25 -1.6) (end -1.25 1.6)
      (stroke (width 0.15) (type solid)) (layer "F.Fab"))
    (fp_line (start 1.25 -1.6) (end -1.25 -1.6)
      (stroke (width 0.15) (type solid)) (layer "F.Fab"))
    (fp_line (start 1.25 -1.6) (end 1.25 1.6)
      (stroke (width 0.15) (type solid)) (layer "F.Fab"))
    (fp_line (start 1.25 1.6) (end -1.25 1.6)
      (stroke (width 0.15) (type solid)) (layer "F.Fab"))
    (pad "1" smd rect (at -0.8 -1.1) (size 1.2 1.4) (layers "F.Cu" "F.Paste" "F.Mask")
      (net 2 "VCC3V3") (pinfunction "EN") (pintype "input") (solder_mask_margin 0.0762))
    (pad "2" smd rect (at -0.8 1.1) (size 1.2 1.4) (layers "F.Cu" "F.Paste" "F.Mask")
      (net 1 "GND") (pinfunction "GND") (pintype "power_in") (solder_mask_margin 0.0762))
    (pad "3" smd rect (at 0.8 1.1) (size 1.2 1.4) (layers "F.Cu" "F.Paste" "F.Mask")
      (net 367 "GCLK100") (pinfunction "OUT") (pintype "output") (solder_mask_margin 0.0762))
    (pad "4" smd rect (at 0.8 -1.1) (size 1.2 1.4) (layers "F.Cu" "F.Paste" "F.Mask")
      (net 2 "VCC3V3") (pinfunction "VDD") (pintype "power_in") (solder_mask_margin 0.0762))
  )
	(footprint "antmicro-footprints:R_0402_1005Metric" (layer "B.Cu")
    (at 95.6 89.75 180)
    (descr "Resistor SMD 0402")
    (tags "resistor SMD 0402")
    (property "Author" "Antmicro")
    (property "License" "Apache-2.0")
    (property "MPN" "CR0402-FX-1022GLF")
    (property "Manufacturer" "Bourns")
    (property "Public" "False")
    (property "Sheetfile" "ethernet.kicad_sch")
    (property "Sheetname" "Ethernet")
    (property "Tolerance" "1%")
    (property "Val" "10k2")
    (property "ki_description" "SMD Chip Resistor")
    (property "ki_keywords" "0402, SMT, RESISTOR, PASSIVE")
    (attr smd)
    (fp_text reference "R11" (at 2.03 0.05 180) (layer "B.SilkS")
        (effects (font (size 0.7 0.7) (thickness 0.127)) (justify mirror))
    )
    (fp_text value "R_10k2_0402" (at 0 -1.17 180) (layer "B.Fab")
        (effects (font (size 1 1) (thickness 0.15)) (justify mirror))
    )
    (fp_text user "${REFERENCE}" (at 0 0 180) (layer "B.Fab")
        (effects (font (size 0.25 0.25) (thickness 0.04)) (justify mirror))
    )
    (fp_text user "License: Apache-2.0" (at -0.95 -5.169) (layer "B.Fab") hide
        (effects (font (size 0.7 0.7) (thickness 0.15)) (justify left bottom mirror))
    )
    (fp_text user "Author: Antmicro" (at -0.95 -4.169) (layer "B.Fab") hide
        (effects (font (size 0.7 0.7) (thickness 0.15)) (justify left bottom mirror))
    )
    (fp_rect (start -0.925 0.47) (end 0.925 -0.47)
      (stroke (width 0.05) (type default)) (fill none) (layer "B.CrtYd"))
    (fp_rect (start -0.5 0.25) (end 0.5 -0.25)
      (stroke (width 0.15) (type solid)) (fill none) (layer "B.Fab"))
    (pad "1" smd roundrect (at -0.48 0 180) (size 0.59 0.64) (layers "B.Cu" "B.Paste" "B.Mask") (roundrect_rratio 0.25)
      (net 164 "/Ethernet/ETH_LED1") (pintype "passive"))
    (pad "2" smd roundrect (at 0.48 0 180) (size 0.59 0.64) (layers "B.Cu" "B.Paste" "B.Mask") (roundrect_rratio 0.25)
      (net 2 "VCC3V3") (pintype "passive"))
  )
)
